(kicad_pcb
	(version 20260206)
	(generator "pcbnew")
	(generator_version "10.0")
	(general
		(thickness 1.6)
		(legacy_teardrops no)
	)
	(paper "A4")
	(title_block
		(title "03242023_DA0F0TMBIJ0_F0T_Motherboard_J_brd_V01_OCP.brd")
		(comment 1 "Grand Teton / footprints 4416-4421 of 6105")
	)
	(layers
		(0 "F.Cu" signal "TOP")
		(4 "In1.Cu" signal "GND")
		(6 "In2.Cu" signal "IN1")
		(8 "In3.Cu" signal "GND1")
		(10 "In4.Cu" signal "IN2")
		(12 "In5.Cu" signal "GND2")
		(14 "In6.Cu" signal "IN3")
		(16 "In7.Cu" signal "GND3")
		(18 "In8.Cu" signal "VCC")
		(20 "In9.Cu" signal "VCC1")
		(22 "In10.Cu" signal "GND4")
		(24 "In11.Cu" signal "IN4")
		(26 "In12.Cu" signal "GND5")
		(28 "In13.Cu" signal "IN5")
		(30 "In14.Cu" signal "GND6")
		(32 "In15.Cu" signal "IN6")
		(34 "In16.Cu" signal "GND7")
		(2 "B.Cu" signal "BOTTOM")
		(9 "F.Adhes" user "F.Adhesive")
		(11 "B.Adhes" user "B.Adhesive")
		(13 "F.Paste" user "Package Geometry/Pastemask Top")
		(15 "B.Paste" user "Package Geometry/Pastemask Bottom")
		(5 "F.SilkS" user "Ref Des/Silkscreen Top")
		(7 "B.SilkS" user "Ref Des/Silkscreen Bottom")
		(1 "F.Mask" user "Board Geometry/Soldermask Top")
		(3 "B.Mask" user "Board Geometry/Soldermask Bottom")
		(17 "Dwgs.User" user "User.Drawings")
		(19 "Cmts.User" user "User.Comments")
		(21 "Eco1.User" user "User.Eco1")
		(23 "Eco2.User" user "User.Eco2")
		(25 "Edge.Cuts" user "Board Geometry/Outline")
		(27 "Margin" user)
		(31 "F.CrtYd" user "Package Geometry/Place Bound Top")
		(29 "B.CrtYd" user "Package Geometry/Place Bound Bottom")
		(35 "F.Fab" user "Ref Des/Assembly Top")
		(33 "B.Fab" user "Ref Des/Assembly Bottom")
	)
	(footprint ""
		(layer "B.Cu")
		(at 450.542914 -8.344916 90)
		(property "Reference" "R414"
			(at 0 0 90)
			(layer "B.SilkS")
			(hide yes)
			(effects
				(font
					(size 1.27 1.27)
				)
				(justify mirror)
			)
		)
		(property "Value" ""
			(at 0 0 90)
			(layer "B.Fab")
			(effects
				(font
					(size 1.27 1.27)
				)
				(justify mirror)
			)
		)
		(duplicate_pad_numbers_are_jumpers no)
		(fp_line
			(start 0.7874 -0.4064)
			(end -0.7874 -0.4064)
			(stroke
				(width 0.1524)
				(type default)
			)
			(layer "B.SilkS")
		)
		(fp_line
			(start -0.7874 -0.4064)
			(end -0.7874 0.4064)
			(stroke
				(width 0.1524)
				(type default)
			)
			(layer "B.SilkS")
		)
		(fp_line
			(start 0.7874 0.4064)
			(end 0.7874 -0.4064)
			(stroke
				(width 0.1524)
				(type default)
			)
			(layer "B.SilkS")
		)
		(fp_line
			(start -0.7874 0.4064)
			(end 0.7874 0.4064)
			(stroke
				(width 0.1524)
				(type default)
			)
			(layer "B.SilkS")
		)
		(fp_line
			(start 0.67945 -0.305054)
			(end 0.12065 -0.305054)
			(stroke
				(width 0.1)
				(type default)
			)
			(layer "B.Fab")
		)
		(fp_line
			(start 0.12065 -0.305054)
			(end 0.12065 -0.2794)
			(stroke
				(width 0.1)
				(type default)
			)
			(layer "B.Fab")
		)
		(fp_line
			(start -0.12065 -0.3048)
			(end -0.67945 -0.3048)
			(stroke
				(width 0.1)
				(type default)
			)
			(layer "B.Fab")
		)
		(fp_line
			(start -0.67945 -0.3048)
			(end -0.67945 0.3048)
			(stroke
				(width 0.1)
				(type default)
			)
			(layer "B.Fab")
		)
		(fp_line
			(start 0.12065 -0.2794)
			(end -0.12065 -0.2794)
			(stroke
				(width 0.1)
				(type default)
			)
			(layer "B.Fab")
		)
		(fp_line
			(start -0.12065 -0.2794)
			(end -0.12065 -0.3048)
			(stroke
				(width 0.1)
				(type default)
			)
			(layer "B.Fab")
		)
		(fp_line
			(start 0.12065 0.2794)
			(end 0.12065 0.3048)
			(stroke
				(width 0.1)
				(type default)
			)
			(layer "B.Fab")
		)
		(fp_line
			(start -0.120396 0.2794)
			(end 0.12065 0.2794)
			(stroke
				(width 0.1)
				(type default)
			)
			(layer "B.Fab")
		)
		(fp_line
			(start 0.67945 0.3048)
			(end 0.67945 -0.305054)
			(stroke
				(width 0.1)
				(type default)
			)
			(layer "B.Fab")
		)
		(fp_line
			(start 0.12065 0.3048)
			(end 0.67945 0.3048)
			(stroke
				(width 0.1)
				(type default)
			)
			(layer "B.Fab")
		)
		(fp_line
			(start -0.120396 0.3048)
			(end -0.120396 0.2794)
			(stroke
				(width 0.1)
				(type default)
			)
			(layer "B.Fab")
		)
		(fp_line
			(start -0.67945 0.3048)
			(end -0.120396 0.3048)
			(stroke
				(width 0.1)
				(type default)
			)
			(layer "B.Fab")
		)
		(pad "1" smd circle
			(at 0.40005 0 270)
			(size 0 0)
			(layers "B.Cu" "B.Mask" "B.Paste")
			(net "P3V3_OCP_SFF")
		)
		(pad "2" smd circle
			(at -0.40005 0 270)
			(size 0 0)
			(layers "B.Cu" "B.Mask" "B.Paste")
			(net "OCP_SFF_ID1")
		)
	)
	(footprint ""
		(layer "B.Cu")
		(at 81.446624 -185.874152 90)
		(property "Reference" "R198"
			(at 0 0 90)
			(layer "B.SilkS")
			(hide yes)
			(effects
				(font
					(size 1.27 1.27)
				)
				(justify mirror)
			)
		)
		(property "Value" ""
			(at 0 0 90)
			(layer "B.Fab")
			(effects
				(font
					(size 1.27 1.27)
				)
				(justify mirror)
			)
		)
		(duplicate_pad_numbers_are_jumpers no)
		(fp_line
			(start 0.7874 -0.4064)
			(end -0.7874 -0.4064)
			(stroke
				(width 0.1524)
				(type default)
			)
			(layer "B.SilkS")
		)
		(fp_line
			(start -0.7874 -0.4064)
			(end -0.7874 0.4064)
			(stroke
				(width 0.1524)
				(type default)
			)
			(layer "B.SilkS")
		)
		(fp_line
			(start 0.7874 0.4064)
			(end 0.7874 -0.4064)
			(stroke
				(width 0.1524)
				(type default)
			)
			(layer "B.SilkS")
		)
		(fp_line
			(start -0.7874 0.4064)
			(end 0.7874 0.4064)
			(stroke
				(width 0.1524)
				(type default)
			)
			(layer "B.SilkS")
		)
		(fp_line
			(start 0.67945 -0.305054)
			(end 0.12065 -0.305054)
			(stroke
				(width 0.1)
				(type default)
			)
			(layer "B.Fab")
		)
		(fp_line
			(start 0.12065 -0.305054)
			(end 0.12065 -0.2794)
			(stroke
				(width 0.1)
				(type default)
			)
			(layer "B.Fab")
		)
		(fp_line
			(start -0.12065 -0.3048)
			(end -0.67945 -0.3048)
			(stroke
				(width 0.1)
				(type default)
			)
			(layer "B.Fab")
		)
		(fp_line
			(start -0.67945 -0.3048)
			(end -0.67945 0.3048)
			(stroke
				(width 0.1)
				(type default)
			)
			(layer "B.Fab")
		)
		(fp_line
			(start 0.12065 -0.2794)
			(end -0.12065 -0.2794)
			(stroke
				(width 0.1)
				(type default)
			)
			(layer "B.Fab")
		)
		(fp_line
			(start -0.12065 -0.2794)
			(end -0.12065 -0.3048)
			(stroke
				(width 0.1)
				(type default)
			)
			(layer "B.Fab")
		)
		(fp_line
			(start 0.12065 0.2794)
			(end 0.12065 0.3048)
			(stroke
				(width 0.1)
				(type default)
			)
			(layer "B.Fab")
		)
		(fp_line
			(start -0.120396 0.2794)
			(end 0.12065 0.2794)
			(stroke
				(width 0.1)
				(type default)
			)
			(layer "B.Fab")
		)
		(fp_line
			(start 0.67945 0.3048)
			(end 0.67945 -0.305054)
			(stroke
				(width 0.1)
				(type default)
			)
			(layer "B.Fab")
		)
		(fp_line
			(start 0.12065 0.3048)
			(end 0.67945 0.3048)
			(stroke
				(width 0.1)
				(type default)
			)
			(layer "B.Fab")
		)
		(fp_line
			(start -0.120396 0.3048)
			(end -0.120396 0.2794)
			(stroke
				(width 0.1)
				(type default)
			)
			(layer "B.Fab")
		)
		(fp_line
			(start -0.67945 0.3048)
			(end -0.120396 0.3048)
			(stroke
				(width 0.1)
				(type default)
			)
			(layer "B.Fab")
		)
		(pad "1" smd circle
			(at 0.40005 0 270)
			(size 0 0)
			(layers "B.Cu" "B.Mask" "B.Paste")
			(net "PVNN_TERM_CPU1")
		)
		(pad "2" smd circle
			(at -0.40005 0 270)
			(size 0 0)
			(layers "B.Cu" "B.Mask" "B.Paste")
			(net "H_CPU1_NMI_LVC1_N")
		)
	)
	(footprint ""
		(layer "B.Cu")
		(at 257.48488 -78.577948 90)
		(property "Reference" "R2357"
			(at 0 0 90)
			(layer "B.SilkS")
			(hide yes)
			(effects
				(font
					(size 1.27 1.27)
				)
				(justify mirror)
			)
		)
		(property "Value" ""
			(at 0 0 90)
			(layer "B.Fab")
			(effects
				(font
					(size 1.27 1.27)
				)
				(justify mirror)
			)
		)
		(duplicate_pad_numbers_are_jumpers no)
		(fp_line
			(start 0.7874 -0.4064)
			(end -0.7874 -0.4064)
			(stroke
				(width 0.1524)
				(type default)
			)
			(layer "B.SilkS")
		)
		(fp_line
			(start -0.7874 -0.4064)
			(end -0.7874 0.4064)
			(stroke
				(width 0.1524)
				(type default)
			)
			(layer "B.SilkS")
		)
		(fp_line
			(start 0.7874 0.4064)
			(end 0.7874 -0.4064)
			(stroke
				(width 0.1524)
				(type default)
			)
			(layer "B.SilkS")
		)
		(fp_line
			(start -0.7874 0.4064)
			(end 0.7874 0.4064)
			(stroke
				(width 0.1524)
				(type default)
			)
			(layer "B.SilkS")
		)
		(fp_line
			(start 0.67945 -0.305054)
			(end 0.12065 -0.305054)
			(stroke
				(width 0.1)
				(type default)
			)
			(layer "B.Fab")
		)
		(fp_line
			(start 0.12065 -0.305054)
			(end 0.12065 -0.2794)
			(stroke
				(width 0.1)
				(type default)
			)
			(layer "B.Fab")
		)
		(fp_line
			(start -0.12065 -0.3048)
			(end -0.67945 -0.3048)
			(stroke
				(width 0.1)
				(type default)
			)
			(layer "B.Fab")
		)
		(fp_line
			(start -0.67945 -0.3048)
			(end -0.67945 0.3048)
			(stroke
				(width 0.1)
				(type default)
			)
			(layer "B.Fab")
		)
		(fp_line
			(start 0.12065 -0.2794)
			(end -0.12065 -0.2794)
			(stroke
				(width 0.1)
				(type default)
			)
			(layer "B.Fab")
		)
		(fp_line
			(start -0.12065 -0.2794)
			(end -0.12065 -0.3048)
			(stroke
				(width 0.1)
				(type default)
			)
			(layer "B.Fab")
		)
		(fp_line
			(start 0.12065 0.2794)
			(end 0.12065 0.3048)
			(stroke
				(width 0.1)
				(type default)
			)
			(layer "B.Fab")
		)
		(fp_line
			(start -0.120396 0.2794)
			(end 0.12065 0.2794)
			(stroke
				(width 0.1)
				(type default)
			)
			(layer "B.Fab")
		)
		(fp_line
			(start 0.67945 0.3048)
			(end 0.67945 -0.305054)
			(stroke
				(width 0.1)
				(type default)
			)
			(layer "B.Fab")
		)
		(fp_line
			(start 0.12065 0.3048)
			(end 0.67945 0.3048)
			(stroke
				(width 0.1)
				(type default)
			)
			(layer "B.Fab")
		)
		(fp_line
			(start -0.120396 0.3048)
			(end -0.120396 0.2794)
			(stroke
				(width 0.1)
				(type default)
			)
			(layer "B.Fab")
		)
		(fp_line
			(start -0.67945 0.3048)
			(end -0.120396 0.3048)
			(stroke
				(width 0.1)
				(type default)
			)
			(layer "B.Fab")
		)
		(pad "1" smd circle
			(at 0.40005 0 270)
			(size 0 0)
			(layers "B.Cu" "B.Mask" "B.Paste")
			(net "P3V3_AUX")
		)
		(pad "2" smd circle
			(at -0.40005 0 270)
			(size 0 0)
			(layers "B.Cu" "B.Mask" "B.Paste")
			(net "PWRGD_P1V05_PCH_AUX_R")
		)
	)
	(footprint ""
		(layer "B.Cu")
		(at 181.755542 -112.97539)
		(property "Reference" "C1122"
			(at 0 0 0)
			(layer "B.SilkS")
			(hide yes)
			(effects
				(font
					(size 1.27 1.27)
				)
				(justify mirror)
			)
		)
		(property "Value" ""
			(at 0 0 0)
			(layer "B.Fab")
			(effects
				(font
					(size 1.27 1.27)
				)
				(justify mirror)
			)
		)
		(duplicate_pad_numbers_are_jumpers no)
		(fp_line
			(start -0.69215 -0.2921)
			(end -0.69215 0.2921)
			(stroke
				(width 0.1524)
				(type default)
			)
			(layer "B.SilkS")
		)
		(fp_line
			(start -0.69215 0.2921)
			(end 0.69215 0.2921)
			(stroke
				(width 0.1524)
				(type default)
			)
			(layer "B.SilkS")
		)
		(fp_line
			(start 0.69215 -0.2921)
			(end -0.69215 -0.2921)
			(stroke
				(width 0.1524)
				(type default)
			)
			(layer "B.SilkS")
		)
		(fp_line
			(start 0.69215 0.2921)
			(end 0.69215 -0.2921)
			(stroke
				(width 0.1524)
				(type default)
			)
			(layer "B.SilkS")
		)
		(fp_line
			(start -0.51435 -0.2794)
			(end -0.51435 0.2794)
			(stroke
				(width 0.1)
				(type default)
			)
			(layer "B.Fab")
		)
		(fp_line
			(start -0.51435 0.2794)
			(end 0.51435 0.2794)
			(stroke
				(width 0.1)
				(type default)
			)
			(layer "B.Fab")
		)
		(fp_line
			(start 0.51435 -0.2794)
			(end -0.51435 -0.2794)
			(stroke
				(width 0.1)
				(type default)
			)
			(layer "B.Fab")
		)
		(fp_line
			(start 0.51435 0.2794)
			(end 0.51435 -0.2794)
			(stroke
				(width 0.1)
				(type default)
			)
			(layer "B.Fab")
		)
		(pad "1" smd circle
			(at 0.40005 0 180)
			(size 0 0)
			(layers "B.Cu" "B.Mask" "B.Paste")
			(net "P3V3_AUX_FPGA_VCCIO2")
		)
		(pad "2" smd circle
			(at -0.40005 0 180)
			(size 0 0)
			(layers "B.Cu" "B.Mask" "B.Paste")
			(net "GND")
		)
		(zone
			(layer "B.Cu")
			(hatch none 0.5)
			(connect_pads
				(clearance 0)
			)
			(min_thickness 0.25)
			(keepout
				(tracks not_allowed)
				(vias allowed)
				(pads allowed)
				(copperpour not_allowed)
				(footprints allowed)
			)
			(placement
				(enabled no)
				(sheetname "")
			)
			(fill
				(thermal_gap 0.5)
				(thermal_bridge_width 0.5)
				(island_removal_mode 0)
			)
			(polygon
				(pts
					(xy 181.946042 -112.88776) (xy 181.854602 -112.829594) (xy 181.655212 -112.829594) (xy 181.565042 -112.88776)
					(xy 181.565042 -113.06302) (xy 181.655212 -113.12144) (xy 181.854602 -113.12144) (xy 181.946042 -113.063274)
				)
			)
		)
	)
	(footprint ""
		(layer "B.Cu")
		(at 434.86832 -47.98314 -90)
		(property "Reference" "Q236"
			(at 1.4224 -1.768348 270)
			(unlocked yes)
			(layer "B.SilkS")
			(effects
				(font
					(size 0.7874 0.5842)
					(thickness 0.1524)
				)
				(justify left mirror)
			)
		)
		(property "Value" ""
			(at 0 0 90)
			(layer "B.Fab")
			(effects
				(font
					(size 1.27 1.27)
				)
				(justify mirror)
			)
		)
		(duplicate_pad_numbers_are_jumpers no)
		(fp_line
			(start -1.332738 1.100074)
			(end 1.332738 1.100074)
			(stroke
				(width 0.1524)
				(type default)
			)
			(layer "B.SilkS")
		)
		(fp_line
			(start 1.332738 1.100074)
			(end 1.332738 -1.100074)
			(stroke
				(width 0.1524)
				(type default)
			)
			(layer "B.SilkS")
		)
		(fp_line
			(start 0 -0.541274)
			(end -0.4826 -1.100074)
			(stroke
				(width 0.1524)
				(type default)
			)
			(layer "B.SilkS")
		)
		(fp_line
			(start -1.332738 -1.100074)
			(end -1.332738 1.100074)
			(stroke
				(width 0.1524)
				(type default)
			)
			(layer "B.SilkS")
		)
		(fp_line
			(start -0.4826 -1.100074)
			(end -1.332738 -1.100074)
			(stroke
				(width 0.1524)
				(type default)
			)
			(layer "B.SilkS")
		)
		(fp_line
			(start 0.4826 -1.100074)
			(end 0 -0.541274)
			(stroke
				(width 0.1524)
				(type default)
			)
			(layer "B.SilkS")
		)
		(fp_line
			(start 1.332738 -1.100074)
			(end 0.4826 -1.100074)
			(stroke
				(width 0.1524)
				(type default)
			)
			(layer "B.SilkS")
		)
		(fp_poly
			(pts
				(xy 2.2352 -0.298958) (xy 2.2352 -1.001014) (xy 1.533144 -0.649986)
			)
			(stroke
				(width 0)
				(type default)
			)
			(fill yes)
			(layer "B.SilkS")
		)
		(fp_line
			(start -0.674878 1.100074)
			(end 0.674878 1.100074)
			(stroke
				(width 0.1)
				(type default)
			)
			(layer "B.Fab")
		)
		(fp_line
			(start 0.674878 1.100074)
			(end 0.674878 -1.100074)
			(stroke
				(width 0.1)
				(type default)
			)
			(layer "B.Fab")
		)
		(fp_line
			(start -0.674878 -1.100074)
			(end -0.674878 1.100074)
			(stroke
				(width 0.1)
				(type default)
			)
			(layer "B.Fab")
		)
		(fp_line
			(start 0.674878 -1.100074)
			(end -0.674878 -1.100074)
			(stroke
				(width 0.1)
				(type default)
			)
			(layer "B.Fab")
		)
		(fp_poly
			(pts
				(xy 2.2352 -0.298958) (xy 2.2352 -1.001014) (xy 1.533144 -0.649986)
			)
			(stroke
				(width 0)
				(type default)
			)
			(fill yes)
			(layer "B.Fab")
		)
		(pad "1" smd rect
			(at 0.94996 -0.649986)
			(size 0.4318 0.508)
			(layers "B.Cu" "B.Mask" "B.Paste")
			(net "GND")
		)
		(pad "2" smd rect
			(at 0.94996 0)
			(size 0.4318 0.508)
			(layers "B.Cu" "B.Mask" "B.Paste")
			(net "PWRGD_P5V")
		)
		(pad "3" smd rect
			(at 0.94996 0.649986)
			(size 0.4318 0.508)
			(layers "B.Cu" "B.Mask" "B.Paste")
			(net "PWRGD_P5V_ISO")
		)
		(pad "4" smd rect
			(at -0.94996 0.649986)
			(size 0.4318 0.508)
			(layers "B.Cu" "B.Mask" "B.Paste")
			(net "GND")
		)
		(pad "5" smd rect
			(at -0.94996 0)
			(size 0.4318 0.508)
			(layers "B.Cu" "B.Mask" "B.Paste")
			(net "PWRGD_P5V_N")
		)
		(pad "6" smd rect
			(at -0.94996 -0.649986)
			(size 0.4318 0.508)
			(layers "B.Cu" "B.Mask" "B.Paste")
			(net "PWRGD_P5V_N")
		)
	)
	(footprint ""
		(layer "B.Cu")
		(at 183.011826 -318.352424)
		(property "Reference" "R77"
			(at 0 0 0)
			(layer "B.SilkS")
			(hide yes)
			(effects
				(font
					(size 1.27 1.27)
				)
				(justify mirror)
			)
		)
		(property "Value" ""
			(at 0 0 0)
			(layer "B.Fab")
			(effects
				(font
					(size 1.27 1.27)
				)
				(justify mirror)
			)
		)
		(duplicate_pad_numbers_are_jumpers no)
		(fp_line
			(start -0.7874 -0.4064)
			(end -0.7874 0.4064)
			(stroke
				(width 0.1524)
				(type default)
			)
			(layer "B.SilkS")
		)
		(fp_line
			(start -0.7874 0.4064)
			(end 0.7874 0.4064)
			(stroke
				(width 0.1524)
				(type default)
			)
			(layer "B.SilkS")
		)
		(fp_line
			(start 0.7874 -0.4064)
			(end -0.7874 -0.4064)
			(stroke
				(width 0.1524)
				(type default)
			)
			(layer "B.SilkS")
		)
		(fp_line
			(start 0.7874 0.4064)
			(end 0.7874 -0.4064)
			(stroke
				(width 0.1524)
				(type default)
			)
			(layer "B.SilkS")
		)
		(fp_line
			(start -0.67945 -0.3048)
			(end -0.67945 0.3048)
			(stroke
				(width 0.1)
				(type default)
			)
			(layer "B.Fab")
		)
		(fp_line
			(start -0.67945 0.3048)
			(end -0.120396 0.3048)
			(stroke
				(width 0.1)
				(type default)
			)
			(layer "B.Fab")
		)
		(fp_line
			(start -0.12065 -0.3048)
			(end -0.67945 -0.3048)
			(stroke
				(width 0.1)
				(type default)
			)
			(layer "B.Fab")
		)
		(fp_line
			(start -0.12065 -0.2794)
			(end -0.12065 -0.3048)
			(stroke
				(width 0.1)
				(type default)
			)
			(layer "B.Fab")
		)
		(fp_line
			(start -0.120396 0.2794)
			(end 0.12065 0.2794)
			(stroke
				(width 0.1)
				(type default)
			)
			(layer "B.Fab")
		)
		(fp_line
			(start -0.120396 0.3048)
			(end -0.120396 0.2794)
			(stroke
				(width 0.1)
				(type default)
			)
			(layer "B.Fab")
		)
		(fp_line
			(start 0.12065 -0.305054)
			(end 0.12065 -0.2794)
			(stroke
				(width 0.1)
				(type default)
			)
			(layer "B.Fab")
		)
		(fp_line
			(start 0.12065 -0.2794)
			(end -0.12065 -0.2794)
			(stroke
				(width 0.1)
				(type default)
			)
			(layer "B.Fab")
		)
		(fp_line
			(start 0.12065 0.2794)
			(end 0.12065 0.3048)
			(stroke
				(width 0.1)
				(type default)
			)
			(layer "B.Fab")
		)
		(fp_line
			(start 0.12065 0.3048)
			(end 0.67945 0.3048)
			(stroke
				(width 0.1)
				(type default)
			)
			(layer "B.Fab")
		)
		(fp_line
			(start 0.67945 -0.305054)
			(end 0.12065 -0.305054)
			(stroke
				(width 0.1)
				(type default)
			)
			(layer "B.Fab")
		)
		(fp_line
			(start 0.67945 0.3048)
			(end 0.67945 -0.305054)
			(stroke
				(width 0.1)
				(type default)
			)
			(layer "B.Fab")
		)
		(pad "1" smd circle
			(at 0.40005 0 180)
			(size 0 0)
			(layers "B.Cu" "B.Mask" "B.Paste")
			(net "PD_CHF_CPU1_DIMM1_SAA")
		)
		(pad "2" smd circle
			(at -0.40005 0 180)
			(size 0 0)
			(layers "B.Cu" "B.Mask" "B.Paste")
			(net "GND")
		)
	)
)
